# BASEBOARD_FAB2 (Tioga Pass) — schematic netlist excerpt (pin names and nets, part order shuffled) for the footprints in the layout excerpt that follows; sources: Cadence DE-HDL packaged netlist, KiCad conversion of Wiwynn_Tioga_Pass_MB.brd

R2T50  RES  1.00K 1% CHIP  pkg 0402  page 93 : A = PD_GTL2104_4_DIR ; B = GND
R6P21  RES  1.00K 1% CHIP  pkg 0402  page 102 : A = FM_DB1200_SMB_SA0 ; B = GND
C7T3  CAP  10UF 4V 20% X6S  pkg 0603LF  page 233 : A = PVPP_GHJ ; B = GND

(kicad_pcb
	(version 20260206)
	(generator "pcbnew")
	(generator_version "10.0")
	(general
		(thickness 1.6)
		(legacy_teardrops no)
	)
	(paper "A4")
	(title_block
		(title "Wiwynn_Tioga_Pass_MB.brd")
		(comment 1 "Tioga Pass / footprints 2989-2991 of 4770")
	)
	(layers
		(0 "F.Cu" signal "TOP")
		(4 "In1.Cu" signal "L2GND")
		(6 "In2.Cu" signal "L3")
		(8 "In3.Cu" signal "L4GND")
		(10 "In4.Cu" signal "L5")
		(12 "In5.Cu" signal "L6GND")
		(14 "In6.Cu" signal "L7VCC")
		(16 "In7.Cu" signal "L8VCC")
		(18 "In8.Cu" signal "L9GND")
		(20 "In9.Cu" signal "L10")
		(22 "In10.Cu" signal "L11GND")
		(24 "In11.Cu" signal "L12")
		(26 "In12.Cu" signal "L13GND")
		(2 "B.Cu" signal "BOTTOM")
		(9 "F.Adhes" user "F.Adhesive")
		(11 "B.Adhes" user "B.Adhesive")
		(13 "F.Paste" user "Package Geometry/Pastemask Top")
		(15 "B.Paste" user "Package Geometry/Pastemask Bottom")
		(5 "F.SilkS" user "Ref Des/Silkscreen Top")
		(7 "B.SilkS" user "Ref Des/Silkscreen Bottom")
		(1 "F.Mask" user "Board Geometry/Soldermask Top")
		(3 "B.Mask" user "Board Geometry/Soldermask Bottom")
		(17 "Dwgs.User" user "User.Drawings")
		(19 "Cmts.User" user "User.Comments")
		(21 "Eco1.User" user "User.Eco1")
		(23 "Eco2.User" user "User.Eco2")
		(25 "Edge.Cuts" user "Board Geometry/Outline")
		(27 "Margin" user)
		(31 "F.CrtYd" user "Package Geometry/Place Bound Top")
		(29 "B.CrtYd" user "Package Geometry/Place Bound Bottom")
		(35 "F.Fab" user "Ref Des/Assembly Top")
		(33 "B.Fab" user "Ref Des/Assembly Bottom")
	)
	(footprint ""
		(layer "B.Cu")
		(at 369.864386 -47.827184 -90)
		(property "Reference" "R2T50"
			(at 0 0 90)
			(layer "B.SilkS")
			(hide yes)
			(effects
				(font
					(size 1.27 1.27)
				)
				(justify mirror)
			)
		)
		(property "Value" ""
			(at 0 0 90)
			(layer "B.Fab")
			(effects
				(font
					(size 1.27 1.27)
				)
				(justify mirror)
			)
		)
		(duplicate_pad_numbers_are_jumpers no)
		(fp_poly
			(pts
				(xy 0.2794 -0.1016) (xy -0.2794 -0.1016) (xy -0.2794 0.9906) (xy 0.2794 0.9906)
			)
			(stroke
				(width 0)
				(type default)
			)
			(fill no)
			(layer "B.CrtYd")
		)
		(fp_line
			(start -0.2794 0.9906)
			(end -0.2794 -0.1016)
			(stroke
				(width 0.1)
				(type default)
			)
			(layer "B.Fab")
		)
		(fp_line
			(start 0.2794 0.9906)
			(end -0.2794 0.9906)
			(stroke
				(width 0.1)
				(type default)
			)
			(layer "B.Fab")
		)
		(fp_line
			(start -0.2794 -0.1016)
			(end 0.2794 -0.1016)
			(stroke
				(width 0.1)
				(type default)
			)
			(layer "B.Fab")
		)
		(fp_line
			(start 0.2794 -0.1016)
			(end 0.2794 0.9906)
			(stroke
				(width 0.1)
				(type default)
			)
			(layer "B.Fab")
		)
		(pad "1" smd rect
			(at 0 0 90)
			(size 0.508 0.508)
			(layers "B.Cu" "B.Mask" "B.Paste")
			(net "PD_GTL2104_4_DIR")
		)
		(pad "2" smd rect
			(at 0 0.889 90)
			(size 0.508 0.508)
			(layers "B.Cu" "B.Mask" "B.Paste")
			(net "GND")
		)
		(zone
			(layer "B.Cu")
			(hatch none 0.5)
			(connect_pads
				(clearance 0)
			)
			(min_thickness 0.25)
			(keepout
				(tracks not_allowed)
				(vias allowed)
				(pads allowed)
				(copperpour not_allowed)
				(footprints allowed)
			)
			(placement
				(enabled no)
				(sheetname "")
			)
			(fill
				(thermal_gap 0.5)
				(thermal_bridge_width 0.5)
				(island_removal_mode 0)
			)
			(polygon
				(pts
					(xy 369.229386 -47.573184) (xy 369.229386 -48.081184) (xy 369.610386 -48.081184) (xy 369.610386 -47.573184)
				)
			)
		)
		(zone
			(layer "B.Cu")
			(hatch none 0.5)
			(connect_pads
				(clearance 0)
			)
			(min_thickness 0.25)
			(keepout
				(tracks allowed)
				(vias not_allowed)
				(pads allowed)
				(copperpour not_allowed)
				(footprints allowed)
			)
			(placement
				(enabled no)
				(sheetname "")
			)
			(fill
				(thermal_gap 0.5)
				(thermal_bridge_width 0.5)
				(island_removal_mode 0)
			)
			(polygon
				(pts
					(xy 369.610386 -47.573184) (xy 369.610386 -48.081184) (xy 369.229386 -48.081184) (xy 369.229386 -47.573184)
				)
			)
		)
	)
	(footprint ""
		(layer "B.Cu")
		(at 153.543 -17.78 -90)
		(property "Reference" "C7T3"
			(at 0 0 90)
			(layer "B.SilkS")
			(hide yes)
			(effects
				(font
					(size 1.27 1.27)
				)
				(justify mirror)
			)
		)
		(property "Value" ""
			(at 0 0 90)
			(layer "B.Fab")
			(effects
				(font
					(size 1.27 1.27)
				)
				(justify mirror)
			)
		)
		(duplicate_pad_numbers_are_jumpers no)
		(fp_poly
			(pts
				(xy 0.4953 -0.2032) (xy -0.4953 -0.2032) (xy -0.4953 1.6002) (xy 0.4953 1.6002)
			)
			(stroke
				(width 0)
				(type default)
			)
			(fill no)
			(layer "B.CrtYd")
		)
		(fp_line
			(start -0.4953 1.6002)
			(end 0.4953 1.6002)
			(stroke
				(width 0.1)
				(type default)
			)
			(layer "B.Fab")
		)
		(fp_line
			(start 0.4953 1.6002)
			(end 0.4953 -0.2032)
			(stroke
				(width 0.1)
				(type default)
			)
			(layer "B.Fab")
		)
		(fp_line
			(start -0.4953 -0.2032)
			(end -0.4953 1.6002)
			(stroke
				(width 0.1)
				(type default)
			)
			(layer "B.Fab")
		)
		(fp_line
			(start 0.4953 -0.2032)
			(end -0.4953 -0.2032)
			(stroke
				(width 0.1)
				(type default)
			)
			(layer "B.Fab")
		)
		(pad "1" smd rect
			(at 0 0 90)
			(size 0.762 0.889)
			(layers "B.Cu" "B.Mask" "B.Paste")
			(net "PVPP_GHJ")
		)
		(pad "2" smd rect
			(at 0 1.397 90)
			(size 0.762 0.889)
			(layers "B.Cu" "B.Mask" "B.Paste")
			(net "GND")
		)
		(zone
			(layer "B.Cu")
			(hatch none 0.5)
			(connect_pads
				(clearance 0)
			)
			(min_thickness 0.25)
			(keepout
				(tracks not_allowed)
				(vias allowed)
				(pads allowed)
				(copperpour not_allowed)
				(footprints allowed)
			)
			(placement
				(enabled no)
				(sheetname "")
			)
			(fill
				(thermal_gap 0.5)
				(thermal_bridge_width 0.5)
				(island_removal_mode 0)
			)
			(polygon
				(pts
					(xy 153.0985 -17.399) (xy 153.0985 -18.161) (xy 152.5905 -18.161) (xy 152.5905 -17.399)
				)
			)
		)
	)
	(footprint ""
		(layer "B.Cu")
		(at 171.069 -74.93)
		(property "Reference" "R6P21"
			(at 0 0 0)
			(layer "B.SilkS")
			(hide yes)
			(effects
				(font
					(size 1.27 1.27)
				)
				(justify mirror)
			)
		)
		(property "Value" ""
			(at 0 0 0)
			(layer "B.Fab")
			(effects
				(font
					(size 1.27 1.27)
				)
				(justify mirror)
			)
		)
		(duplicate_pad_numbers_are_jumpers no)
		(fp_poly
			(pts
				(xy 0.2794 -0.1016) (xy -0.2794 -0.1016) (xy -0.2794 0.9906) (xy 0.2794 0.9906)
			)
			(stroke
				(width 0)
				(type default)
			)
			(fill no)
			(layer "B.CrtYd")
		)
		(fp_line
			(start -0.2794 -0.1016)
			(end 0.2794 -0.1016)
			(stroke
				(width 0.1)
				(type default)
			)
			(layer "B.Fab")
		)
		(fp_line
			(start -0.2794 0.9906)
			(end -0.2794 -0.1016)
			(stroke
				(width 0.1)
				(type default)
			)
			(layer "B.Fab")
		)
		(fp_line
			(start 0.2794 -0.1016)
			(end 0.2794 0.9906)
			(stroke
				(width 0.1)
				(type default)
			)
			(layer "B.Fab")
		)
		(fp_line
			(start 0.2794 0.9906)
			(end -0.2794 0.9906)
			(stroke
				(width 0.1)
				(type default)
			)
			(layer "B.Fab")
		)
		(pad "1" smd rect
			(at 0 0 180)
			(size 0.508 0.508)
			(layers "B.Cu" "B.Mask" "B.Paste")
			(net "FM_DB1200_SMB_SA0")
		)
		(pad "2" smd rect
			(at 0 0.889 180)
			(size 0.508 0.508)
			(layers "B.Cu" "B.Mask" "B.Paste")
			(net "GND")
		)
		(zone
			(layer "B.Cu")
			(hatch none 0.5)
			(connect_pads
				(clearance 0)
			)
			(min_thickness 0.25)
			(keepout
				(tracks allowed)
				(vias not_allowed)
				(pads allowed)
				(copperpour not_allowed)
				(footprints allowed)
			)
			(placement
				(enabled no)
				(sheetname "")
			)
			(fill
				(thermal_gap 0.5)
				(thermal_bridge_width 0.5)
				(island_removal_mode 0)
			)
			(polygon
				(pts
					(xy 171.323 -74.676) (xy 170.815 -74.676) (xy 170.815 -74.295) (xy 171.323 -74.295)
				)
			)
		)
		(zone
			(layer "B.Cu")
			(hatch none 0.5)
			(connect_pads
				(clearance 0)
			)
			(min_thickness 0.25)
			(keepout
				(tracks not_allowed)
				(vias allowed)
				(pads allowed)
				(copperpour not_allowed)
				(footprints allowed)
			)
			(placement
				(enabled no)
				(sheetname "")
			)
			(fill
				(thermal_gap 0.5)
				(thermal_bridge_width 0.5)
				(island_removal_mode 0)
			)
			(polygon
				(pts
					(xy 171.323 -74.295) (xy 170.815 -74.295) (xy 170.815 -74.676) (xy 171.323 -74.676)
				)
			)
		)
	)
)
